(kicad_pcb
	(version 20260206)
	(generator "pcbnew")
	(generator_version "10.0")
	(general
		(thickness 1.6)
		(legacy_teardrops no)
	)
	(paper "A4")
	(title_block
		(title "01162023_DA0F0TEBIF0_F0T_Expander_BD_F_brd_V02_OCP.brd")
		(comment 1 "Grand Teton / footprints 5173-5178 of 9728")
	)
	(layers
		(0 "F.Cu" signal "TOP")
		(4 "In1.Cu" signal "GND")
		(6 "In2.Cu" signal "VCC")
		(8 "In3.Cu" signal "VCC1")
		(10 "In4.Cu" signal "GND1")
		(12 "In5.Cu" signal "IN1")
		(14 "In6.Cu" signal "GND2")
		(16 "In7.Cu" signal "IN2")
		(18 "In8.Cu" signal "GND3")
		(20 "In9.Cu" signal "IN3")
		(22 "In10.Cu" signal "GND4")
		(24 "In11.Cu" signal "IN4")
		(26 "In12.Cu" signal "GND5")
		(28 "In13.Cu" signal "IN5")
		(30 "In14.Cu" signal "GND6")
		(32 "In15.Cu" signal "IN6")
		(34 "In16.Cu" signal "GND7")
		(2 "B.Cu" signal "BOTTOM")
		(9 "F.Adhes" user "F.Adhesive")
		(11 "B.Adhes" user "B.Adhesive")
		(13 "F.Paste" user "Package Geometry/Pastemask Top")
		(15 "B.Paste" user "Package Geometry/Pastemask Bottom")
		(5 "F.SilkS" user "Ref Des/Silkscreen Top")
		(7 "B.SilkS" user "Ref Des/Silkscreen Bottom")
		(1 "F.Mask" user "Board Geometry/Soldermask Top")
		(3 "B.Mask" user "Board Geometry/Soldermask Bottom")
		(17 "Dwgs.User" user "User.Drawings")
		(19 "Cmts.User" user "User.Comments")
		(21 "Eco1.User" user "User.Eco1")
		(23 "Eco2.User" user "User.Eco2")
		(25 "Edge.Cuts" user "Board Geometry/Outline")
		(27 "Margin" user)
		(31 "F.CrtYd" user "Package Geometry/Place Bound Top")
		(29 "B.CrtYd" user "Package Geometry/Place Bound Bottom")
		(35 "F.Fab" user "Ref Des/Assembly Top")
		(33 "B.Fab" user "Ref Des/Assembly Bottom")
	)
	(footprint ""
		(layer "F.Cu")
		(at 91.311984 -100.20935 90)
		(property "Reference" "U80"
			(at -0.38735 2.364486 90)
			(unlocked yes)
			(layer "F.SilkS")
			(effects
				(font
					(size 0.7874 0.5842)
					(thickness 0.1524)
				)
			)
		)
		(property "Value" ""
			(at 0 0 90)
			(layer "F.Fab")
			(effects
				(font
					(size 1.27 1.27)
				)
			)
		)
		(duplicate_pad_numbers_are_jumpers no)
		(fp_line
			(start 1.500124 -1.500124)
			(end 1.500124 -1.004062)
			(stroke
				(width 0.1524)
				(type default)
			)
			(layer "F.SilkS")
		)
		(fp_line
			(start 1.004062 -1.500124)
			(end 1.500124 -1.500124)
			(stroke
				(width 0.1524)
				(type default)
			)
			(layer "F.SilkS")
		)
		(fp_line
			(start -1.500124 -1.500124)
			(end -1.004062 -1.500124)
			(stroke
				(width 0.1524)
				(type default)
			)
			(layer "F.SilkS")
		)
		(fp_line
			(start -1.500124 -1.004062)
			(end -1.500124 -1.500124)
			(stroke
				(width 0.1524)
				(type default)
			)
			(layer "F.SilkS")
		)
		(fp_line
			(start 1.500124 1.004062)
			(end 1.500124 1.500124)
			(stroke
				(width 0.1524)
				(type default)
			)
			(layer "F.SilkS")
		)
		(fp_line
			(start 1.500124 1.500124)
			(end 1.004062 1.500124)
			(stroke
				(width 0.1524)
				(type default)
			)
			(layer "F.SilkS")
		)
		(fp_line
			(start -1.004062 1.500124)
			(end -1.500124 1.500124)
			(stroke
				(width 0.1524)
				(type default)
			)
			(layer "F.SilkS")
		)
		(fp_line
			(start -1.500124 1.500124)
			(end -1.500124 1.004062)
			(stroke
				(width 0.1524)
				(type default)
			)
			(layer "F.SilkS")
		)
		(fp_poly
			(pts
				(xy -1.972818 -2.316734) (xy -2.69113 -1.598422) (xy -1.613408 -1.239266)
			)
			(stroke
				(width 0)
				(type default)
			)
			(fill yes)
			(layer "F.SilkS")
		)
		(fp_line
			(start 1.500124 -1.500124)
			(end 1.500124 1.500124)
			(stroke
				(width 0.1)
				(type default)
			)
			(layer "F.Fab")
		)
		(fp_line
			(start -1.500124 -1.500124)
			(end 1.500124 -1.500124)
			(stroke
				(width 0.1)
				(type default)
			)
			(layer "F.Fab")
		)
		(fp_line
			(start 1.500124 1.500124)
			(end -1.500124 1.500124)
			(stroke
				(width 0.1)
				(type default)
			)
			(layer "F.Fab")
		)
		(fp_line
			(start -1.500124 1.500124)
			(end -1.500124 -1.500124)
			(stroke
				(width 0.1)
				(type default)
			)
			(layer "F.Fab")
		)
		(fp_poly
			(pts
				(xy -2.847848 -1.258062) (xy -2.847848 -0.242062) (xy -1.831848 -0.750062)
			)
			(stroke
				(width 0)
				(type default)
			)
			(fill yes)
			(layer "F.Fab")
		)
		(pad "1" smd rect
			(at -1.400048 -0.750062)
			(size 0.2286 0.6096)
			(layers "F.Cu" "F.Mask" "F.Paste")
			(net "NIC1_ADC_A1")
		)
		(pad "2" smd rect
			(at -1.400048 -0.249936)
			(size 0.2286 0.6096)
			(layers "F.Cu" "F.Mask" "F.Paste")
			(net "NIC1_ADC_A0")
		)
		(pad "3" smd rect
			(at -1.400048 0.249936)
			(size 0.2286 0.6096)
			(layers "F.Cu" "F.Mask" "F.Paste")
			(net "NIC1_ADC_ALERT_N")
		)
		(pad "4" smd rect
			(at -1.400048 0.750062)
			(size 0.2286 0.6096)
			(layers "F.Cu" "F.Mask" "F.Paste")
			(net "SMB_NIC1_ADC_SDA")
		)
		(pad "5" smd rect
			(at -0.750062 1.400048 90)
			(size 0.2286 0.6096)
			(layers "F.Cu" "F.Mask" "F.Paste")
			(net "SMB_NIC1_ADC_SCL")
		)
		(pad "6" smd rect
			(at -0.249936 1.400048 90)
			(size 0.2286 0.6096)
			(layers "F.Cu" "F.Mask" "F.Paste")
			(net "Net_8660")
		)
		(pad "7" smd rect
			(at 0.249936 1.400048 90)
			(size 0.2286 0.6096)
			(layers "F.Cu" "F.Mask" "F.Paste")
			(net "Net_8659")
		)
		(pad "8" smd rect
			(at 0.750062 1.400048 90)
			(size 0.2286 0.6096)
			(layers "F.Cu" "F.Mask" "F.Paste")
			(net "Net_8658")
		)
		(pad "9" smd rect
			(at 1.400048 0.750062)
			(size 0.2286 0.6096)
			(layers "F.Cu" "F.Mask" "F.Paste")
			(net "P3V3_AUX")
		)
		(pad "10" smd rect
			(at 1.400048 0.249936)
			(size 0.2286 0.6096)
			(layers "F.Cu" "F.Mask" "F.Paste")
			(net "GND")
		)
		(pad "11" smd rect
			(at 1.400048 -0.249936)
			(size 0.2286 0.6096)
			(layers "F.Cu" "F.Mask" "F.Paste")
			(net "P12V_NIC1_R")
		)
		(pad "12" smd rect
			(at 1.400048 -0.750062)
			(size 0.2286 0.6096)
			(layers "F.Cu" "F.Mask" "F.Paste")
			(net "P12V_NIC1_VIN_N")
		)
		(pad "13" smd rect
			(at 0.750062 -1.400048 90)
			(size 0.2286 0.6096)
			(layers "F.Cu" "F.Mask" "F.Paste")
			(net "P12V_NIC1_VIN_P")
		)
		(pad "14" smd rect
			(at 0.249936 -1.400048 90)
			(size 0.2286 0.6096)
			(layers "F.Cu" "F.Mask" "F.Paste")
			(net "Net_8657")
		)
		(pad "15" smd rect
			(at -0.249936 -1.400048 90)
			(size 0.2286 0.6096)
			(layers "F.Cu" "F.Mask" "F.Paste")
			(net "Net_8656")
		)
		(pad "16" smd rect
			(at -0.750062 -1.400048 90)
			(size 0.2286 0.6096)
			(layers "F.Cu" "F.Mask" "F.Paste")
			(net "Net_8655")
		)
		(pad "TH" smd rect
			(at 0 0 90)
			(size 1.7018 1.7018)
			(layers "F.Cu" "F.Mask" "F.Paste")
			(net "GND")
		)
		(zone
			(layer "F.Cu")
			(hatch none 0.5)
			(connect_pads
				(clearance 0)
			)
			(min_thickness 0.25)
			(keepout
				(tracks not_allowed)
				(vias allowed)
				(pads allowed)
				(copperpour not_allowed)
				(footprints allowed)
			)
			(placement
				(enabled no)
				(sheetname "")
			)
			(fill
				(thermal_gap 0.5)
				(thermal_bridge_width 0.5)
				(island_removal_mode 0)
			)
			(polygon
				(pts
					(xy 91.286584 -99.164902) (xy 90.267536 -99.164902) (xy 90.267536 -101.253798) (xy 92.356432 -101.253798)
					(xy 92.356432 -99.164902) (xy 91.311984 -99.164902) (xy 91.311984 -99.30765) (xy 92.213684 -99.30765)
					(xy 92.213684 -101.11105) (xy 90.410284 -101.11105) (xy 90.410284 -99.30765) (xy 91.286584 -99.30765)
				)
			)
		)
	)
	(footprint ""
		(layer "F.Cu")
		(at 164.920676 -70.307454 90)
		(property "Reference" "PC848"
			(at 0 0 90)
			(layer "F.SilkS")
			(hide yes)
			(effects
				(font
					(size 1.27 1.27)
				)
			)
		)
		(property "Value" ""
			(at 0 0 90)
			(layer "F.Fab")
			(effects
				(font
					(size 1.27 1.27)
				)
			)
		)
		(duplicate_pad_numbers_are_jumpers no)
		(fp_line
			(start 0.7874 -0.4064)
			(end 0.7874 0.4064)
			(stroke
				(width 0.1524)
				(type default)
			)
			(layer "F.SilkS")
		)
		(fp_line
			(start -0.7874 -0.4064)
			(end 0.7874 -0.4064)
			(stroke
				(width 0.1524)
				(type default)
			)
			(layer "F.SilkS")
		)
		(fp_line
			(start 0.7874 0.4064)
			(end -0.7874 0.4064)
			(stroke
				(width 0.1524)
				(type default)
			)
			(layer "F.SilkS")
		)
		(fp_line
			(start -0.7874 0.4064)
			(end -0.7874 -0.4064)
			(stroke
				(width 0.1524)
				(type default)
			)
			(layer "F.SilkS")
		)
		(fp_line
			(start -0.12065 -0.305054)
			(end -0.12065 -0.2794)
			(stroke
				(width 0.1)
				(type default)
			)
			(layer "F.Fab")
		)
		(fp_line
			(start -0.67945 -0.305054)
			(end -0.12065 -0.305054)
			(stroke
				(width 0.1)
				(type default)
			)
			(layer "F.Fab")
		)
		(fp_line
			(start 0.67945 -0.3048)
			(end 0.67945 0.3048)
			(stroke
				(width 0.1)
				(type default)
			)
			(layer "F.Fab")
		)
		(fp_line
			(start 0.12065 -0.3048)
			(end 0.67945 -0.3048)
			(stroke
				(width 0.1)
				(type default)
			)
			(layer "F.Fab")
		)
		(fp_line
			(start 0.12065 -0.2794)
			(end 0.12065 -0.3048)
			(stroke
				(width 0.1)
				(type default)
			)
			(layer "F.Fab")
		)
		(fp_line
			(start -0.12065 -0.2794)
			(end 0.12065 -0.2794)
			(stroke
				(width 0.1)
				(type default)
			)
			(layer "F.Fab")
		)
		(fp_line
			(start 0.120396 0.2794)
			(end -0.12065 0.2794)
			(stroke
				(width 0.1)
				(type default)
			)
			(layer "F.Fab")
		)
		(fp_line
			(start -0.12065 0.2794)
			(end -0.12065 0.3048)
			(stroke
				(width 0.1)
				(type default)
			)
			(layer "F.Fab")
		)
		(fp_line
			(start 0.67945 0.3048)
			(end 0.120396 0.3048)
			(stroke
				(width 0.1)
				(type default)
			)
			(layer "F.Fab")
		)
		(fp_line
			(start 0.120396 0.3048)
			(end 0.120396 0.2794)
			(stroke
				(width 0.1)
				(type default)
			)
			(layer "F.Fab")
		)
		(fp_line
			(start -0.12065 0.3048)
			(end -0.67945 0.3048)
			(stroke
				(width 0.1)
				(type default)
			)
			(layer "F.Fab")
		)
		(fp_line
			(start -0.67945 0.3048)
			(end -0.67945 -0.305054)
			(stroke
				(width 0.1)
				(type default)
			)
			(layer "F.Fab")
		)
		(pad "1" smd circle
			(at -0.40005 0 90)
			(size 0 0)
			(layers "F.Cu" "F.Mask" "F.Paste")
			(net "P12V_AUX")
		)
		(pad "2" smd circle
			(at 0.40005 0 90)
			(size 0 0)
			(layers "F.Cu" "F.Mask" "F.Paste")
			(net "GND")
		)
	)
	(footprint ""
		(layer "F.Cu")
		(at 136.33958 -152.71115 90)
		(property "Reference" "R703"
			(at 0 0 90)
			(layer "F.SilkS")
			(hide yes)
			(effects
				(font
					(size 1.27 1.27)
				)
			)
		)
		(property "Value" ""
			(at 0 0 90)
			(layer "F.Fab")
			(effects
				(font
					(size 1.27 1.27)
				)
			)
		)
		(duplicate_pad_numbers_are_jumpers no)
		(fp_line
			(start 0.7874 -0.4064)
			(end 0.7874 0.4064)
			(stroke
				(width 0.1524)
				(type default)
			)
			(layer "F.SilkS")
		)
		(fp_line
			(start -0.7874 -0.4064)
			(end 0.7874 -0.4064)
			(stroke
				(width 0.1524)
				(type default)
			)
			(layer "F.SilkS")
		)
		(fp_line
			(start 0.7874 0.4064)
			(end -0.7874 0.4064)
			(stroke
				(width 0.1524)
				(type default)
			)
			(layer "F.SilkS")
		)
		(fp_line
			(start -0.7874 0.4064)
			(end -0.7874 -0.4064)
			(stroke
				(width 0.1524)
				(type default)
			)
			(layer "F.SilkS")
		)
		(fp_line
			(start -0.12065 -0.305054)
			(end -0.12065 -0.2794)
			(stroke
				(width 0.1)
				(type default)
			)
			(layer "F.Fab")
		)
		(fp_line
			(start -0.67945 -0.305054)
			(end -0.12065 -0.305054)
			(stroke
				(width 0.1)
				(type default)
			)
			(layer "F.Fab")
		)
		(fp_line
			(start 0.67945 -0.3048)
			(end 0.67945 0.3048)
			(stroke
				(width 0.1)
				(type default)
			)
			(layer "F.Fab")
		)
		(fp_line
			(start 0.12065 -0.3048)
			(end 0.67945 -0.3048)
			(stroke
				(width 0.1)
				(type default)
			)
			(layer "F.Fab")
		)
		(fp_line
			(start 0.12065 -0.2794)
			(end 0.12065 -0.3048)
			(stroke
				(width 0.1)
				(type default)
			)
			(layer "F.Fab")
		)
		(fp_line
			(start -0.12065 -0.2794)
			(end 0.12065 -0.2794)
			(stroke
				(width 0.1)
				(type default)
			)
			(layer "F.Fab")
		)
		(fp_line
			(start 0.120396 0.2794)
			(end -0.12065 0.2794)
			(stroke
				(width 0.1)
				(type default)
			)
			(layer "F.Fab")
		)
		(fp_line
			(start -0.12065 0.2794)
			(end -0.12065 0.3048)
			(stroke
				(width 0.1)
				(type default)
			)
			(layer "F.Fab")
		)
		(fp_line
			(start 0.67945 0.3048)
			(end 0.120396 0.3048)
			(stroke
				(width 0.1)
				(type default)
			)
			(layer "F.Fab")
		)
		(fp_line
			(start 0.120396 0.3048)
			(end 0.120396 0.2794)
			(stroke
				(width 0.1)
				(type default)
			)
			(layer "F.Fab")
		)
		(fp_line
			(start -0.12065 0.3048)
			(end -0.67945 0.3048)
			(stroke
				(width 0.1)
				(type default)
			)
			(layer "F.Fab")
		)
		(fp_line
			(start -0.67945 0.3048)
			(end -0.67945 -0.305054)
			(stroke
				(width 0.1)
				(type default)
			)
			(layer "F.Fab")
		)
		(pad "1" smd circle
			(at -0.40005 0 90)
			(size 0 0)
			(layers "F.Cu" "F.Mask" "F.Paste")
			(net "NIC2_ADC_A0")
		)
		(pad "2" smd circle
			(at 0.40005 0 90)
			(size 0 0)
			(layers "F.Cu" "F.Mask" "F.Paste")
			(net "P3V3_AUX")
		)
	)
	(footprint ""
		(layer "F.Cu")
		(at 134.720076 -15.649956 180)
		(property "Reference" "H129"
			(at -2.106422 2.488184 0)
			(unlocked yes)
			(layer "B.SilkS")
			(effects
				(font
					(size 0.7874 0.5842)
					(thickness 0.1524)
				)
				(justify left mirror)
			)
		)
		(property "Value" ""
			(at 0 0 180)
			(layer "F.Fab")
			(effects
				(font
					(size 1.27 1.27)
				)
			)
		)
		(duplicate_pad_numbers_are_jumpers no)
		(pad "1" thru_hole rect
			(at 0 0 180)
			(size 4.2164 5.0038)
			(drill 2.0066
				(offset 0.099822 0)
			)
			(layers "*.Cu" "*.Mask")
			(remove_unused_layers no)
			(net "Net_8534")
			(clearance -0.8509)
			(padstack
				(mode front_inner_back)
				(layer "Inner"
					(shape circle)
					(size 4.0132 4.0132)
					(clearance -0.7493)
				)
				(layer "B.Cu"
					(shape circle)
					(size 4.0132 4.0132)
					(clearance -0.7493)
				)
			)
		)
	)
	(footprint ""
		(layer "F.Cu")
		(at 238.15929 -209.564478 -90)
		(property "Reference" "R476"
			(at 0 0 270)
			(layer "F.SilkS")
			(hide yes)
			(effects
				(font
					(size 1.27 1.27)
				)
			)
		)
		(property "Value" ""
			(at 0 0 270)
			(layer "F.Fab")
			(effects
				(font
					(size 1.27 1.27)
				)
			)
		)
		(duplicate_pad_numbers_are_jumpers no)
		(fp_line
			(start -0.7874 0.4064)
			(end -0.7874 -0.4064)
			(stroke
				(width 0.1524)
				(type default)
			)
			(layer "F.SilkS")
		)
		(fp_line
			(start 0.7874 0.4064)
			(end -0.7874 0.4064)
			(stroke
				(width 0.1524)
				(type default)
			)
			(layer "F.SilkS")
		)
		(fp_line
			(start -0.7874 -0.4064)
			(end 0.7874 -0.4064)
			(stroke
				(width 0.1524)
				(type default)
			)
			(layer "F.SilkS")
		)
		(fp_line
			(start 0.7874 -0.4064)
			(end 0.7874 0.4064)
			(stroke
				(width 0.1524)
				(type default)
			)
			(layer "F.SilkS")
		)
		(fp_line
			(start -0.67945 0.3048)
			(end -0.67945 -0.305054)
			(stroke
				(width 0.1)
				(type default)
			)
			(layer "F.Fab")
		)
		(fp_line
			(start -0.12065 0.3048)
			(end -0.67945 0.3048)
			(stroke
				(width 0.1)
				(type default)
			)
			(layer "F.Fab")
		)
		(fp_line
			(start 0.120396 0.3048)
			(end 0.120396 0.2794)
			(stroke
				(width 0.1)
				(type default)
			)
			(layer "F.Fab")
		)
		(fp_line
			(start 0.67945 0.3048)
			(end 0.120396 0.3048)
			(stroke
				(width 0.1)
				(type default)
			)
			(layer "F.Fab")
		)
		(fp_line
			(start -0.12065 0.2794)
			(end -0.12065 0.3048)
			(stroke
				(width 0.1)
				(type default)
			)
			(layer "F.Fab")
		)
		(fp_line
			(start 0.120396 0.2794)
			(end -0.12065 0.2794)
			(stroke
				(width 0.1)
				(type default)
			)
			(layer "F.Fab")
		)
		(fp_line
			(start -0.12065 -0.2794)
			(end 0.12065 -0.2794)
			(stroke
				(width 0.1)
				(type default)
			)
			(layer "F.Fab")
		)
		(fp_line
			(start 0.12065 -0.2794)
			(end 0.12065 -0.3048)
			(stroke
				(width 0.1)
				(type default)
			)
			(layer "F.Fab")
		)
		(fp_line
			(start 0.12065 -0.3048)
			(end 0.67945 -0.3048)
			(stroke
				(width 0.1)
				(type default)
			)
			(layer "F.Fab")
		)
		(fp_line
			(start 0.67945 -0.3048)
			(end 0.67945 0.3048)
			(stroke
				(width 0.1)
				(type default)
			)
			(layer "F.Fab")
		)
		(fp_line
			(start -0.67945 -0.305054)
			(end -0.12065 -0.305054)
			(stroke
				(width 0.1)
				(type default)
			)
			(layer "F.Fab")
		)
		(fp_line
			(start -0.12065 -0.305054)
			(end -0.12065 -0.2794)
			(stroke
				(width 0.1)
				(type default)
			)
			(layer "F.Fab")
		)
		(pad "1" smd circle
			(at -0.40005 0 270)
			(size 0 0)
			(layers "F.Cu" "F.Mask" "F.Paste")
			(net "P5V_AUX_SCALED")
		)
		(pad "2" smd circle
			(at 0.40005 0 270)
			(size 0 0)
			(layers "F.Cu" "F.Mask" "F.Paste")
			(net "GND")
		)
	)
	(footprint ""
		(layer "F.Cu")
		(at 224.022158 -83.659472 180)
		(property "Reference" "R4352"
			(at 0 0 180)
			(layer "F.SilkS")
			(hide yes)
			(effects
				(font
					(size 1.27 1.27)
				)
			)
		)
		(property "Value" ""
			(at 0 0 180)
			(layer "F.Fab")
			(effects
				(font
					(size 1.27 1.27)
				)
			)
		)
		(duplicate_pad_numbers_are_jumpers no)
		(fp_line
			(start 0.7874 0.4064)
			(end -0.7874 0.4064)
			(stroke
				(width 0.1524)
				(type default)
			)
			(layer "F.SilkS")
		)
		(fp_line
			(start 0.7874 -0.4064)
			(end 0.7874 0.4064)
			(stroke
				(width 0.1524)
				(type default)
			)
			(layer "F.SilkS")
		)
		(fp_line
			(start -0.7874 0.4064)
			(end -0.7874 -0.4064)
			(stroke
				(width 0.1524)
				(type default)
			)
			(layer "F.SilkS")
		)
		(fp_line
			(start -0.7874 -0.4064)
			(end 0.7874 -0.4064)
			(stroke
				(width 0.1524)
				(type default)
			)
			(layer "F.SilkS")
		)
		(fp_line
			(start 0.67945 0.3048)
			(end 0.120396 0.3048)
			(stroke
				(width 0.1)
				(type default)
			)
			(layer "F.Fab")
		)
		(fp_line
			(start 0.67945 -0.3048)
			(end 0.67945 0.3048)
			(stroke
				(width 0.1)
				(type default)
			)
			(layer "F.Fab")
		)
		(fp_line
			(start 0.12065 -0.2794)
			(end 0.12065 -0.3048)
			(stroke
				(width 0.1)
				(type default)
			)
			(layer "F.Fab")
		)
		(fp_line
			(start 0.12065 -0.3048)
			(end 0.67945 -0.3048)
			(stroke
				(width 0.1)
				(type default)
			)
			(layer "F.Fab")
		)
		(fp_line
			(start 0.120396 0.3048)
			(end 0.120396 0.2794)
			(stroke
				(width 0.1)
				(type default)
			)
			(layer "F.Fab")
		)
		(fp_line
			(start 0.120396 0.2794)
			(end -0.12065 0.2794)
			(stroke
				(width 0.1)
				(type default)
			)
			(layer "F.Fab")
		)
		(fp_line
			(start -0.12065 0.3048)
			(end -0.67945 0.3048)
			(stroke
				(width 0.1)
				(type default)
			)
			(layer "F.Fab")
		)
		(fp_line
			(start -0.12065 0.2794)
			(end -0.12065 0.3048)
			(stroke
				(width 0.1)
				(type default)
			)
			(layer "F.Fab")
		)
		(fp_line
			(start -0.12065 -0.2794)
			(end 0.12065 -0.2794)
			(stroke
				(width 0.1)
				(type default)
			)
			(layer "F.Fab")
		)
		(fp_line
			(start -0.12065 -0.305054)
			(end -0.12065 -0.2794)
			(stroke
				(width 0.1)
				(type default)
			)
			(layer "F.Fab")
		)
		(fp_line
			(start -0.67945 0.3048)
			(end -0.67945 -0.305054)
			(stroke
				(width 0.1)
				(type default)
			)
			(layer "F.Fab")
		)
		(fp_line
			(start -0.67945 -0.305054)
			(end -0.12065 -0.305054)
			(stroke
				(width 0.1)
				(type default)
			)
			(layer "F.Fab")
		)
		(pad "1" smd circle
			(at -0.40005 0 180)
			(size 0 0)
			(layers "F.Cu" "F.Mask" "F.Paste")
			(net "P3V3_AUX")
		)
		(pad "2" smd circle
			(at 0.40005 0 180)
			(size 0 0)
			(layers "F.Cu" "F.Mask" "F.Paste")
			(net "SSD14_LED_R")
		)
	)
)
